(kicad_pcb
	(version 20260206)
	(generator "pcbnew")
	(generator_version "10.0")
	(general
		(thickness 1.6)
		(legacy_teardrops no)
	)
	(paper "A4")
	(title_block
		(title "Bryce Canyon_SCC_16316-1_OCP.brd")
		(comment 1 "Bryce Canyon / footprint 146 of 1561 (CN2), pads 148-219 of 342")
	)
	(layers
		(0 "F.Cu" signal "TOP")
		(4 "In1.Cu" signal "L2GND")
		(6 "In2.Cu" signal "L3")
		(8 "In3.Cu" signal "L4VCC")
		(10 "In4.Cu" signal "L5VCC")
		(12 "In5.Cu" signal "L6")
		(14 "In6.Cu" signal "L7GND")
		(2 "B.Cu" signal "BOTTOM")
		(9 "F.Adhes" user "F.Adhesive")
		(11 "B.Adhes" user "B.Adhesive")
		(13 "F.Paste" user "Package Geometry/Pastemask Top")
		(15 "B.Paste" user "Package Geometry/Pastemask Bottom")
		(5 "F.SilkS" user "Ref Des/Silkscreen Top")
		(7 "B.SilkS" user "Ref Des/Silkscreen Bottom")
		(1 "F.Mask" user "Board Geometry/Soldermask Top")
		(3 "B.Mask" user "Board Geometry/Soldermask Bottom")
		(17 "Dwgs.User" user "User.Drawings")
		(19 "Cmts.User" user "User.Comments")
		(21 "Eco1.User" user "User.Eco1")
		(23 "Eco2.User" user "User.Eco2")
		(25 "Edge.Cuts" user "Board Geometry/Outline")
		(27 "Margin" user)
		(31 "F.CrtYd" user "Package Geometry/Place Bound Top")
		(29 "B.CrtYd" user "Package Geometry/Place Bound Bottom")
		(35 "F.Fab" user "Ref Des/Assembly Top")
		(33 "B.Fab" user "Ref Des/Assembly Bottom")
	)
	(footprint ""
		(layer "F.Cu")
		(at 86.000082 -3.800094)
		(property "Reference" "CN2"
			(at 0 0 0)
			(layer "F.SilkS")
			(hide yes)
			(effects
				(font
					(size 1.27 1.27)
				)
			)
		)
		(property "Value" "AMP-CONN342-10R-3-GP"
			(at -12.8905 -12.5222 0)
			(unlocked yes)
			(layer "F.Fab")
			(hide yes)
			(effects
				(font
					(size 1.016 1.016)
					(thickness 0.1524)
				)
			)
		)
		(property "Device Type" "PREFIT-342P-648260H400"
			(at -12.8905 -14.0462 0)
			(unlocked yes)
			(layer "F.Fab")
			(hide yes)
			(effects
				(font
					(size 1.016 1.016)
					(thickness 0.1524)
				)
			)
		)
		(duplicate_pad_numbers_are_jumpers no)
		(pad "E4" thru_hole circle
			(at 5.40004 -5.999988)
			(size 0.762 0.762)
			(drill 0.359918)
			(layers "*.Cu" "*.Mask")
			(remove_unused_layers no)
			(net "PHY_SCC_TO_DPB_15_DP")
			(clearance 0.1651)
			(thermal_gap 0.1651)
		)
		(pad "E5" thru_hole circle
			(at 7.199884 -7.199884)
			(size 0.762 0.762)
			(drill 0.359918)
			(layers "*.Cu" "*.Mask")
			(remove_unused_layers no)
			(net "PHY_SCC_TO_DPB_16_DP")
			(clearance 0.1651)
			(thermal_gap 0.1651)
		)
		(pad "E6" thru_hole circle
			(at 8.999982 -5.999988)
			(size 0.762 0.762)
			(drill 0.359918)
			(layers "*.Cu" "*.Mask")
			(remove_unused_layers no)
			(net "PHY_SCC_TO_DPB_17_DP")
			(clearance 0.1651)
			(thermal_gap 0.1651)
		)
		(pad "E7" thru_hole circle
			(at 10.80008 -7.199884)
			(size 0.762 0.762)
			(drill 0.359918)
			(layers "*.Cu" "*.Mask")
			(remove_unused_layers no)
			(net "PHY_SCC_TO_DPB_18_DP")
			(clearance 0.1651)
			(thermal_gap 0.1651)
		)
		(pad "E8" thru_hole circle
			(at 12.599924 -5.999988)
			(size 0.762 0.762)
			(drill 0.359918)
			(layers "*.Cu" "*.Mask")
			(remove_unused_layers no)
			(net "PHY_SCC_TO_DPB_19_DP")
			(clearance 0.1651)
			(thermal_gap 0.1651)
		)
		(pad "E9" thru_hole circle
			(at 14.400022 -7.199884)
			(size 0.762 0.762)
			(drill 0.359918)
			(layers "*.Cu" "*.Mask")
			(remove_unused_layers no)
			(net "PHY_SCC_TO_DPB_20_DP")
			(clearance 0.1651)
			(thermal_gap 0.1651)
		)
		(pad "E10" thru_hole circle
			(at 16.20012 -5.999988)
			(size 0.762 0.762)
			(drill 0.359918)
			(layers "*.Cu" "*.Mask")
			(remove_unused_layers no)
			(net "PHY_SCC_TO_DPB_21_DP")
			(clearance 0.1651)
			(thermal_gap 0.1651)
		)
		(pad "E11" thru_hole circle
			(at 17.999964 -7.199884)
			(size 0.762 0.762)
			(drill 0.359918)
			(layers "*.Cu" "*.Mask")
			(remove_unused_layers no)
			(net "PHY_SCC_TO_DPB_22_DP")
			(clearance 0.1651)
			(thermal_gap 0.1651)
		)
		(pad "E12" thru_hole circle
			(at 19.800062 -5.999988)
			(size 0.762 0.762)
			(drill 0.359918)
			(layers "*.Cu" "*.Mask")
			(remove_unused_layers no)
			(net "PHY_SCC_TO_DPB_23_DP")
			(clearance 0.1651)
			(thermal_gap 0.1651)
		)
		(pad "E13" thru_hole circle
			(at 21.599906 -7.199884)
			(size 0.762 0.762)
			(drill 0.359918)
			(layers "*.Cu" "*.Mask")
			(remove_unused_layers no)
			(net "PHY_SCC_TO_DPB_24_DP")
			(clearance 0.1651)
			(thermal_gap 0.1651)
		)
		(pad "E14" thru_hole circle
			(at 23.400004 -5.999988)
			(size 0.762 0.762)
			(drill 0.359918)
			(layers "*.Cu" "*.Mask")
			(remove_unused_layers no)
			(net "PHY_SCC_TO_DPB_25_DP")
			(clearance 0.1651)
			(thermal_gap 0.1651)
		)
		(pad "E15" thru_hole circle
			(at 25.200102 -7.199884)
			(size 0.762 0.762)
			(drill 0.359918)
			(layers "*.Cu" "*.Mask")
			(remove_unused_layers no)
			(net "PHY_SCC_TO_DPB_26_DP")
			(clearance 0.1651)
			(thermal_gap 0.1651)
		)
		(pad "E16" thru_hole circle
			(at 26.999946 -5.999988)
			(size 0.762 0.762)
			(drill 0.359918)
			(layers "*.Cu" "*.Mask")
			(remove_unused_layers no)
			(net "PHY_SCC_TO_DPB_27_DP")
			(clearance 0.1651)
			(thermal_gap 0.1651)
		)
		(pad "E17" thru_hole circle
			(at 28.800044 -7.199884)
			(size 0.762 0.762)
			(drill 0.359918)
			(layers "*.Cu" "*.Mask")
			(remove_unused_layers no)
			(net "PHY_SCC_TO_DPB_32_DP")
			(clearance 0.1651)
			(thermal_gap 0.1651)
		)
		(pad "E18" thru_hole circle
			(at 30.599888 -5.999988)
			(size 0.762 0.762)
			(drill 0.359918)
			(layers "*.Cu" "*.Mask")
			(remove_unused_layers no)
			(net "PHY_SCC_TO_DPB_33_DP")
			(clearance 0.1651)
			(thermal_gap 0.1651)
		)
		(pad "E19" thru_hole circle
			(at 32.399986 -7.199884)
			(size 0.762 0.762)
			(drill 0.359918)
			(layers "*.Cu" "*.Mask")
			(remove_unused_layers no)
			(net "PHY_SCC_TO_DPB_34_DP")
			(clearance 0.1651)
			(thermal_gap 0.1651)
		)
		(pad "E20" thru_hole circle
			(at 34.200084 -5.999988)
			(size 0.762 0.762)
			(drill 0.359918)
			(layers "*.Cu" "*.Mask")
			(remove_unused_layers no)
			(net "PHY_SCC_TO_DPB_35_DP")
			(clearance 0.1651)
			(thermal_gap 0.1651)
		)
		(pad "E21" thru_hole circle
			(at 35.999928 -7.199884)
			(size 0.762 0.762)
			(drill 0.359918)
			(layers "*.Cu" "*.Mask")
			(remove_unused_layers no)
			(net "PHY_SCC_TO_DPB_36_DP")
			(clearance 0.1651)
			(thermal_gap 0.1651)
		)
		(pad "E22" thru_hole circle
			(at 37.800026 -5.999988)
			(size 0.762 0.762)
			(drill 0.359918)
			(layers "*.Cu" "*.Mask")
			(remove_unused_layers no)
			(net "PHY_SCC_TO_DPB_37_DP")
			(clearance 0.1651)
			(thermal_gap 0.1651)
		)
		(pad "E23" thru_hole circle
			(at 39.600124 -7.199884)
			(size 0.762 0.762)
			(drill 0.359918)
			(layers "*.Cu" "*.Mask")
			(remove_unused_layers no)
			(net "PHY_SCC_TO_DPB_38_DP")
			(clearance 0.1651)
			(thermal_gap 0.1651)
		)
		(pad "E24" thru_hole circle
			(at 41.399968 -5.999988)
			(size 0.762 0.762)
			(drill 0.359918)
			(layers "*.Cu" "*.Mask")
			(remove_unused_layers no)
			(net "PHY_SCC_TO_DPB_39_DP")
			(clearance 0.1651)
			(thermal_gap 0.1651)
		)
		(pad "E25" thru_hole circle
			(at 43.200066 -7.199884)
			(size 0.762 0.762)
			(drill 0.359918)
			(layers "*.Cu" "*.Mask")
			(remove_unused_layers no)
			(net "PHY_SCC_TO_DPB_28_DP")
			(clearance 0.1651)
			(thermal_gap 0.1651)
		)
		(pad "E26" thru_hole circle
			(at 44.99991 -5.999988)
			(size 0.762 0.762)
			(drill 0.359918)
			(layers "*.Cu" "*.Mask")
			(remove_unused_layers no)
			(net "PHY_SCC_TO_DPB_29_DP")
			(clearance 0.1651)
			(thermal_gap 0.1651)
		)
		(pad "E27" thru_hole circle
			(at 46.800008 -7.199884)
			(size 0.762 0.762)
			(drill 0.359918)
			(layers "*.Cu" "*.Mask")
			(remove_unused_layers no)
			(net "PHY_SCC_TO_DPB_30_DP")
			(clearance 0.1651)
			(thermal_gap 0.1651)
		)
		(pad "E28" thru_hole circle
			(at 48.600106 -5.999988)
			(size 0.762 0.762)
			(drill 0.359918)
			(layers "*.Cu" "*.Mask")
			(remove_unused_layers no)
			(net "PHY_SCC_TO_DPB_31_DP")
			(clearance 0.1651)
			(thermal_gap 0.1651)
		)
		(pad "E29" thru_hole circle
			(at 50.39995 -7.199884)
			(size 0.762 0.762)
			(drill 0.359918)
			(layers "*.Cu" "*.Mask")
			(remove_unused_layers no)
			(net "PHY_SCC_TO_DPB_0_DP")
			(clearance 0.1651)
			(thermal_gap 0.1651)
		)
		(pad "E30" thru_hole circle
			(at 52.200048 -5.999988)
			(size 0.762 0.762)
			(drill 0.359918)
			(layers "*.Cu" "*.Mask")
			(remove_unused_layers no)
			(net "PHY_SCC_TO_DPB_1_DP")
			(clearance 0.1651)
			(thermal_gap 0.1651)
		)
		(pad "E31" thru_hole circle
			(at 53.999892 -7.199884)
			(size 0.762 0.762)
			(drill 0.359918)
			(layers "*.Cu" "*.Mask")
			(remove_unused_layers no)
			(net "PHY_SCC_TO_DPB_2_DP")
			(clearance 0.1651)
			(thermal_gap 0.1651)
		)
		(pad "E32" thru_hole circle
			(at 55.79999 -5.999988)
			(size 0.762 0.762)
			(drill 0.359918)
			(layers "*.Cu" "*.Mask")
			(remove_unused_layers no)
			(net "PHY_SCC_TO_DPB_3_DP")
			(clearance 0.1651)
			(thermal_gap 0.1651)
		)
		(pad "E33" thru_hole circle
			(at 57.600088 -7.199884)
			(size 0.762 0.762)
			(drill 0.359918)
			(layers "*.Cu" "*.Mask")
			(remove_unused_layers no)
			(net "PHY_SCC_TO_DPB_4_DP")
			(clearance 0.1651)
			(thermal_gap 0.1651)
		)
		(pad "E34" thru_hole circle
			(at 59.399932 -5.999988)
			(size 0.762 0.762)
			(drill 0.359918)
			(layers "*.Cu" "*.Mask")
			(remove_unused_layers no)
			(net "PHY_SCC_TO_DPB_5_DP")
			(clearance 0.1651)
			(thermal_gap 0.1651)
		)
		(pad "E35" thru_hole circle
			(at 61.20003 -7.199884)
			(size 0.762 0.762)
			(drill 0.359918)
			(layers "*.Cu" "*.Mask")
			(remove_unused_layers no)
			(net "PHY_SCC_TO_DPB_6_DP")
			(clearance 0.1651)
			(thermal_gap 0.1651)
		)
		(pad "E36" thru_hole circle
			(at 62.999874 -5.999988)
			(size 0.762 0.762)
			(drill 0.359918)
			(layers "*.Cu" "*.Mask")
			(remove_unused_layers no)
			(net "PHY_SCC_TO_DPB_7_DP")
			(clearance 0.1651)
			(thermal_gap 0.1651)
		)
		(pad "F1" thru_hole circle
			(at 0 -8.599932)
			(size 0.762 0.762)
			(drill 0.359918)
			(layers "*.Cu" "*.Mask")
			(remove_unused_layers no)
			(net "PHY_SCC_TO_DPB_12_DN")
			(clearance 0.1651)
			(thermal_gap 0.1651)
		)
		(pad "F2" thru_hole circle
			(at 1.800098 -7.400036)
			(size 0.762 0.762)
			(drill 0.359918)
			(layers "*.Cu" "*.Mask")
			(remove_unused_layers no)
			(net "PHY_SCC_TO_DPB_13_DN")
			(clearance 0.1651)
			(thermal_gap 0.1651)
		)
		(pad "F3" thru_hole circle
			(at 3.599942 -8.599932)
			(size 0.762 0.762)
			(drill 0.359918)
			(layers "*.Cu" "*.Mask")
			(remove_unused_layers no)
			(net "PHY_SCC_TO_DPB_14_DN")
			(clearance 0.1651)
			(thermal_gap 0.1651)
		)
		(pad "F4" thru_hole circle
			(at 5.40004 -7.400036)
			(size 0.762 0.762)
			(drill 0.359918)
			(layers "*.Cu" "*.Mask")
			(remove_unused_layers no)
			(net "PHY_SCC_TO_DPB_15_DN")
			(clearance 0.1651)
			(thermal_gap 0.1651)
		)
		(pad "F5" thru_hole circle
			(at 7.199884 -8.599932)
			(size 0.762 0.762)
			(drill 0.359918)
			(layers "*.Cu" "*.Mask")
			(remove_unused_layers no)
			(net "PHY_SCC_TO_DPB_16_DN")
			(clearance 0.1651)
			(thermal_gap 0.1651)
		)
		(pad "F6" thru_hole circle
			(at 8.999982 -7.400036)
			(size 0.762 0.762)
			(drill 0.359918)
			(layers "*.Cu" "*.Mask")
			(remove_unused_layers no)
			(net "PHY_SCC_TO_DPB_17_DN")
			(clearance 0.1651)
			(thermal_gap 0.1651)
		)
		(pad "F7" thru_hole circle
			(at 10.80008 -8.599932)
			(size 0.762 0.762)
			(drill 0.359918)
			(layers "*.Cu" "*.Mask")
			(remove_unused_layers no)
			(net "PHY_SCC_TO_DPB_18_DN")
			(clearance 0.1651)
			(thermal_gap 0.1651)
		)
		(pad "F8" thru_hole circle
			(at 12.599924 -7.400036)
			(size 0.762 0.762)
			(drill 0.359918)
			(layers "*.Cu" "*.Mask")
			(remove_unused_layers no)
			(net "PHY_SCC_TO_DPB_19_DN")
			(clearance 0.1651)
			(thermal_gap 0.1651)
		)
		(pad "F9" thru_hole circle
			(at 14.400022 -8.599932)
			(size 0.762 0.762)
			(drill 0.359918)
			(layers "*.Cu" "*.Mask")
			(remove_unused_layers no)
			(net "PHY_SCC_TO_DPB_20_DN")
			(clearance 0.1651)
			(thermal_gap 0.1651)
		)
		(pad "F10" thru_hole circle
			(at 16.20012 -7.400036)
			(size 0.762 0.762)
			(drill 0.359918)
			(layers "*.Cu" "*.Mask")
			(remove_unused_layers no)
			(net "PHY_SCC_TO_DPB_21_DN")
			(clearance 0.1651)
			(thermal_gap 0.1651)
		)
		(pad "F11" thru_hole circle
			(at 17.999964 -8.599932)
			(size 0.762 0.762)
			(drill 0.359918)
			(layers "*.Cu" "*.Mask")
			(remove_unused_layers no)
			(net "PHY_SCC_TO_DPB_22_DN")
			(clearance 0.1651)
			(thermal_gap 0.1651)
		)
		(pad "F12" thru_hole circle
			(at 19.800062 -7.400036)
			(size 0.762 0.762)
			(drill 0.359918)
			(layers "*.Cu" "*.Mask")
			(remove_unused_layers no)
			(net "PHY_SCC_TO_DPB_23_DN")
			(clearance 0.1651)
			(thermal_gap 0.1651)
		)
		(pad "F13" thru_hole circle
			(at 21.599906 -8.599932)
			(size 0.762 0.762)
			(drill 0.359918)
			(layers "*.Cu" "*.Mask")
			(remove_unused_layers no)
			(net "PHY_SCC_TO_DPB_24_DN")
			(clearance 0.1651)
			(thermal_gap 0.1651)
		)
		(pad "F14" thru_hole circle
			(at 23.400004 -7.400036)
			(size 0.762 0.762)
			(drill 0.359918)
			(layers "*.Cu" "*.Mask")
			(remove_unused_layers no)
			(net "PHY_SCC_TO_DPB_25_DN")
			(clearance 0.1651)
			(thermal_gap 0.1651)
		)
		(pad "F15" thru_hole circle
			(at 25.200102 -8.599932)
			(size 0.762 0.762)
			(drill 0.359918)
			(layers "*.Cu" "*.Mask")
			(remove_unused_layers no)
			(net "PHY_SCC_TO_DPB_26_DN")
			(clearance 0.1651)
			(thermal_gap 0.1651)
		)
		(pad "F16" thru_hole circle
			(at 26.999946 -7.400036)
			(size 0.762 0.762)
			(drill 0.359918)
			(layers "*.Cu" "*.Mask")
			(remove_unused_layers no)
			(net "PHY_SCC_TO_DPB_27_DN")
			(clearance 0.1651)
			(thermal_gap 0.1651)
		)
		(pad "F17" thru_hole circle
			(at 28.800044 -8.599932)
			(size 0.762 0.762)
			(drill 0.359918)
			(layers "*.Cu" "*.Mask")
			(remove_unused_layers no)
			(net "PHY_SCC_TO_DPB_32_DN")
			(clearance 0.1651)
			(thermal_gap 0.1651)
		)
		(pad "F18" thru_hole circle
			(at 30.599888 -7.400036)
			(size 0.762 0.762)
			(drill 0.359918)
			(layers "*.Cu" "*.Mask")
			(remove_unused_layers no)
			(net "PHY_SCC_TO_DPB_33_DN")
			(clearance 0.1651)
			(thermal_gap 0.1651)
		)
		(pad "F19" thru_hole circle
			(at 32.399986 -8.599932)
			(size 0.762 0.762)
			(drill 0.359918)
			(layers "*.Cu" "*.Mask")
			(remove_unused_layers no)
			(net "PHY_SCC_TO_DPB_34_DN")
			(clearance 0.1651)
			(thermal_gap 0.1651)
		)
		(pad "F20" thru_hole circle
			(at 34.200084 -7.400036)
			(size 0.762 0.762)
			(drill 0.359918)
			(layers "*.Cu" "*.Mask")
			(remove_unused_layers no)
			(net "PHY_SCC_TO_DPB_35_DN")
			(clearance 0.1651)
			(thermal_gap 0.1651)
		)
		(pad "F21" thru_hole circle
			(at 35.999928 -8.599932)
			(size 0.762 0.762)
			(drill 0.359918)
			(layers "*.Cu" "*.Mask")
			(remove_unused_layers no)
			(net "PHY_SCC_TO_DPB_36_DN")
			(clearance 0.1651)
			(thermal_gap 0.1651)
		)
		(pad "F22" thru_hole circle
			(at 37.800026 -7.400036)
			(size 0.762 0.762)
			(drill 0.359918)
			(layers "*.Cu" "*.Mask")
			(remove_unused_layers no)
			(net "PHY_SCC_TO_DPB_37_DN")
			(clearance 0.1651)
			(thermal_gap 0.1651)
		)
		(pad "F23" thru_hole circle
			(at 39.600124 -8.599932)
			(size 0.762 0.762)
			(drill 0.359918)
			(layers "*.Cu" "*.Mask")
			(remove_unused_layers no)
			(net "PHY_SCC_TO_DPB_38_DN")
			(clearance 0.1651)
			(thermal_gap 0.1651)
		)
		(pad "F24" thru_hole circle
			(at 41.399968 -7.400036)
			(size 0.762 0.762)
			(drill 0.359918)
			(layers "*.Cu" "*.Mask")
			(remove_unused_layers no)
			(net "PHY_SCC_TO_DPB_39_DN")
			(clearance 0.1651)
			(thermal_gap 0.1651)
		)
		(pad "F25" thru_hole circle
			(at 43.200066 -8.599932)
			(size 0.762 0.762)
			(drill 0.359918)
			(layers "*.Cu" "*.Mask")
			(remove_unused_layers no)
			(net "PHY_SCC_TO_DPB_28_DN")
			(clearance 0.1651)
			(thermal_gap 0.1651)
		)
		(pad "F26" thru_hole circle
			(at 44.99991 -7.400036)
			(size 0.762 0.762)
			(drill 0.359918)
			(layers "*.Cu" "*.Mask")
			(remove_unused_layers no)
			(net "PHY_SCC_TO_DPB_29_DN")
			(clearance 0.1651)
			(thermal_gap 0.1651)
		)
		(pad "F27" thru_hole circle
			(at 46.800008 -8.599932)
			(size 0.762 0.762)
			(drill 0.359918)
			(layers "*.Cu" "*.Mask")
			(remove_unused_layers no)
			(net "PHY_SCC_TO_DPB_30_DN")
			(clearance 0.1651)
			(thermal_gap 0.1651)
		)
		(pad "F28" thru_hole circle
			(at 48.600106 -7.400036)
			(size 0.762 0.762)
			(drill 0.359918)
			(layers "*.Cu" "*.Mask")
			(remove_unused_layers no)
			(net "PHY_SCC_TO_DPB_31_DN")
			(clearance 0.1651)
			(thermal_gap 0.1651)
		)
		(pad "F29" thru_hole circle
			(at 50.39995 -8.599932)
			(size 0.762 0.762)
			(drill 0.359918)
			(layers "*.Cu" "*.Mask")
			(remove_unused_layers no)
			(net "PHY_SCC_TO_DPB_0_DN")
			(clearance 0.1651)
			(thermal_gap 0.1651)
		)
		(pad "F30" thru_hole circle
			(at 52.200048 -7.400036)
			(size 0.762 0.762)
			(drill 0.359918)
			(layers "*.Cu" "*.Mask")
			(remove_unused_layers no)
			(net "PHY_SCC_TO_DPB_1_DN")
			(clearance 0.1651)
			(thermal_gap 0.1651)
		)
		(pad "F31" thru_hole circle
			(at 53.999892 -8.599932)
			(size 0.762 0.762)
			(drill 0.359918)
			(layers "*.Cu" "*.Mask")
			(remove_unused_layers no)
			(net "PHY_SCC_TO_DPB_2_DN")
			(clearance 0.1651)
			(thermal_gap 0.1651)
		)
		(pad "F32" thru_hole circle
			(at 55.79999 -7.400036)
			(size 0.762 0.762)
			(drill 0.359918)
			(layers "*.Cu" "*.Mask")
			(remove_unused_layers no)
			(net "PHY_SCC_TO_DPB_3_DN")
			(clearance 0.1651)
			(thermal_gap 0.1651)
		)
		(pad "F33" thru_hole circle
			(at 57.600088 -8.599932)
			(size 0.762 0.762)
			(drill 0.359918)
			(layers "*.Cu" "*.Mask")
			(remove_unused_layers no)
			(net "PHY_SCC_TO_DPB_4_DN")
			(clearance 0.1651)
			(thermal_gap 0.1651)
		)
		(pad "F34" thru_hole circle
			(at 59.399932 -7.400036)
			(size 0.762 0.762)
			(drill 0.359918)
			(layers "*.Cu" "*.Mask")
			(remove_unused_layers no)
			(net "PHY_SCC_TO_DPB_5_DN")
			(clearance 0.1651)
			(thermal_gap 0.1651)
		)
		(pad "F35" thru_hole circle
			(at 61.20003 -8.599932)
			(size 0.762 0.762)
			(drill 0.359918)
			(layers "*.Cu" "*.Mask")
			(remove_unused_layers no)
			(net "PHY_SCC_TO_DPB_6_DN")
			(clearance 0.1651)
			(thermal_gap 0.1651)
		)
		(pad "F36" thru_hole circle
			(at 62.999874 -7.400036)
			(size 0.762 0.762)
			(drill 0.359918)
			(layers "*.Cu" "*.Mask")
			(remove_unused_layers no)
			(net "PHY_SCC_TO_DPB_7_DN")
			(clearance 0.1651)
			(thermal_gap 0.1651)
		)
		(pad "GND1" thru_hole circle
			(at 0 -2.500122)
			(size 0.762 0.762)
			(drill 0.359918)
			(layers "*.Cu" "*.Mask")
			(remove_unused_layers no)
			(net "GND")
			(clearance 0.1651)
			(thermal_gap 0.1651)
		)
		(pad "GND2" thru_hole circle
			(at 0 -6.100064)
			(size 0.762 0.762)
			(drill 0.359918)
			(layers "*.Cu" "*.Mask")
			(remove_unused_layers no)
			(net "GND")
			(clearance 0.1651)
			(thermal_gap 0.1651)
		)
		(pad "GND3" thru_hole circle
			(at 0 -9.700006)
			(size 0.762 0.762)
			(drill 0.359918)
			(layers "*.Cu" "*.Mask")
			(remove_unused_layers no)
			(net "GND")
			(clearance 0.1651)
			(thermal_gap 0.1651)
		)
	)
)
